(kicad_pcb
	(version 20260206)
	(generator "pcbnew")
	(generator_version "10.0")
	(general
		(thickness 1.6)
		(legacy_teardrops no)
	)
	(paper "A4")
	(title_block
		(title "01162023_DA0F0TEBIF0_F0T_Expander_BD_F_brd_V02_OCP.brd")
		(comment 1 "Grand Teton / footprints 7004-7010 of 9728")
	)
	(layers
		(0 "F.Cu" signal "TOP")
		(4 "In1.Cu" signal "GND")
		(6 "In2.Cu" signal "VCC")
		(8 "In3.Cu" signal "VCC1")
		(10 "In4.Cu" signal "GND1")
		(12 "In5.Cu" signal "IN1")
		(14 "In6.Cu" signal "GND2")
		(16 "In7.Cu" signal "IN2")
		(18 "In8.Cu" signal "GND3")
		(20 "In9.Cu" signal "IN3")
		(22 "In10.Cu" signal "GND4")
		(24 "In11.Cu" signal "IN4")
		(26 "In12.Cu" signal "GND5")
		(28 "In13.Cu" signal "IN5")
		(30 "In14.Cu" signal "GND6")
		(32 "In15.Cu" signal "IN6")
		(34 "In16.Cu" signal "GND7")
		(2 "B.Cu" signal "BOTTOM")
		(9 "F.Adhes" user "F.Adhesive")
		(11 "B.Adhes" user "B.Adhesive")
		(13 "F.Paste" user "Package Geometry/Pastemask Top")
		(15 "B.Paste" user "Package Geometry/Pastemask Bottom")
		(5 "F.SilkS" user "Ref Des/Silkscreen Top")
		(7 "B.SilkS" user "Ref Des/Silkscreen Bottom")
		(1 "F.Mask" user "Board Geometry/Soldermask Top")
		(3 "B.Mask" user "Board Geometry/Soldermask Bottom")
		(17 "Dwgs.User" user "User.Drawings")
		(19 "Cmts.User" user "User.Comments")
		(21 "Eco1.User" user "User.Eco1")
		(23 "Eco2.User" user "User.Eco2")
		(25 "Edge.Cuts" user "Board Geometry/Outline")
		(27 "Margin" user)
		(31 "F.CrtYd" user "Package Geometry/Place Bound Top")
		(29 "B.CrtYd" user "Package Geometry/Place Bound Bottom")
		(35 "F.Fab" user "Ref Des/Assembly Top")
		(33 "B.Fab" user "Ref Des/Assembly Bottom")
	)
	(footprint ""
		(layer "F.Cu")
		(at 386.90804 -158.3944 180)
		(property "Reference" "R317"
			(at 0 0 180)
			(layer "F.SilkS")
			(hide yes)
			(effects
				(font
					(size 1.27 1.27)
				)
			)
		)
		(property "Value" ""
			(at 0 0 180)
			(layer "F.Fab")
			(effects
				(font
					(size 1.27 1.27)
				)
			)
		)
		(duplicate_pad_numbers_are_jumpers no)
		(fp_line
			(start 0.7874 0.4064)
			(end -0.7874 0.4064)
			(stroke
				(width 0.1524)
				(type default)
			)
			(layer "F.SilkS")
		)
		(fp_line
			(start 0.7874 -0.4064)
			(end 0.7874 0.4064)
			(stroke
				(width 0.1524)
				(type default)
			)
			(layer "F.SilkS")
		)
		(fp_line
			(start -0.7874 0.4064)
			(end -0.7874 -0.4064)
			(stroke
				(width 0.1524)
				(type default)
			)
			(layer "F.SilkS")
		)
		(fp_line
			(start -0.7874 -0.4064)
			(end 0.7874 -0.4064)
			(stroke
				(width 0.1524)
				(type default)
			)
			(layer "F.SilkS")
		)
		(fp_line
			(start 0.67945 0.3048)
			(end 0.120396 0.3048)
			(stroke
				(width 0.1)
				(type default)
			)
			(layer "F.Fab")
		)
		(fp_line
			(start 0.67945 -0.3048)
			(end 0.67945 0.3048)
			(stroke
				(width 0.1)
				(type default)
			)
			(layer "F.Fab")
		)
		(fp_line
			(start 0.12065 -0.2794)
			(end 0.12065 -0.3048)
			(stroke
				(width 0.1)
				(type default)
			)
			(layer "F.Fab")
		)
		(fp_line
			(start 0.12065 -0.3048)
			(end 0.67945 -0.3048)
			(stroke
				(width 0.1)
				(type default)
			)
			(layer "F.Fab")
		)
		(fp_line
			(start 0.120396 0.3048)
			(end 0.120396 0.2794)
			(stroke
				(width 0.1)
				(type default)
			)
			(layer "F.Fab")
		)
		(fp_line
			(start 0.120396 0.2794)
			(end -0.12065 0.2794)
			(stroke
				(width 0.1)
				(type default)
			)
			(layer "F.Fab")
		)
		(fp_line
			(start -0.12065 0.3048)
			(end -0.67945 0.3048)
			(stroke
				(width 0.1)
				(type default)
			)
			(layer "F.Fab")
		)
		(fp_line
			(start -0.12065 0.2794)
			(end -0.12065 0.3048)
			(stroke
				(width 0.1)
				(type default)
			)
			(layer "F.Fab")
		)
		(fp_line
			(start -0.12065 -0.2794)
			(end 0.12065 -0.2794)
			(stroke
				(width 0.1)
				(type default)
			)
			(layer "F.Fab")
		)
		(fp_line
			(start -0.12065 -0.305054)
			(end -0.12065 -0.2794)
			(stroke
				(width 0.1)
				(type default)
			)
			(layer "F.Fab")
		)
		(fp_line
			(start -0.67945 0.3048)
			(end -0.67945 -0.305054)
			(stroke
				(width 0.1)
				(type default)
			)
			(layer "F.Fab")
		)
		(fp_line
			(start -0.67945 -0.305054)
			(end -0.12065 -0.305054)
			(stroke
				(width 0.1)
				(type default)
			)
			(layer "F.Fab")
		)
		(pad "1" smd circle
			(at -0.40005 0 180)
			(size 0 0)
			(layers "F.Cu" "F.Mask" "F.Paste")
			(net "NIC6_LD_N")
		)
		(pad "2" smd circle
			(at 0.40005 0 180)
			(size 0 0)
			(layers "F.Cu" "F.Mask" "F.Paste")
			(net "P3V3_NIC6")
		)
	)
	(footprint ""
		(layer "F.Cu")
		(at 350.380554 -88.359234)
		(property "Reference" "R1592"
			(at 0 0 0)
			(layer "F.SilkS")
			(hide yes)
			(effects
				(font
					(size 1.27 1.27)
				)
			)
		)
		(property "Value" ""
			(at 0 0 0)
			(layer "F.Fab")
			(effects
				(font
					(size 1.27 1.27)
				)
			)
		)
		(duplicate_pad_numbers_are_jumpers no)
		(fp_line
			(start -0.7874 -0.4064)
			(end 0.7874 -0.4064)
			(stroke
				(width 0.1524)
				(type default)
			)
			(layer "F.SilkS")
		)
		(fp_line
			(start -0.7874 0.4064)
			(end -0.7874 -0.4064)
			(stroke
				(width 0.1524)
				(type default)
			)
			(layer "F.SilkS")
		)
		(fp_line
			(start 0.7874 -0.4064)
			(end 0.7874 0.4064)
			(stroke
				(width 0.1524)
				(type default)
			)
			(layer "F.SilkS")
		)
		(fp_line
			(start 0.7874 0.4064)
			(end -0.7874 0.4064)
			(stroke
				(width 0.1524)
				(type default)
			)
			(layer "F.SilkS")
		)
		(fp_line
			(start -0.67945 -0.305054)
			(end -0.12065 -0.305054)
			(stroke
				(width 0.1)
				(type default)
			)
			(layer "F.Fab")
		)
		(fp_line
			(start -0.67945 0.3048)
			(end -0.67945 -0.305054)
			(stroke
				(width 0.1)
				(type default)
			)
			(layer "F.Fab")
		)
		(fp_line
			(start -0.12065 -0.305054)
			(end -0.12065 -0.2794)
			(stroke
				(width 0.1)
				(type default)
			)
			(layer "F.Fab")
		)
		(fp_line
			(start -0.12065 -0.2794)
			(end 0.12065 -0.2794)
			(stroke
				(width 0.1)
				(type default)
			)
			(layer "F.Fab")
		)
		(fp_line
			(start -0.12065 0.2794)
			(end -0.12065 0.3048)
			(stroke
				(width 0.1)
				(type default)
			)
			(layer "F.Fab")
		)
		(fp_line
			(start -0.12065 0.3048)
			(end -0.67945 0.3048)
			(stroke
				(width 0.1)
				(type default)
			)
			(layer "F.Fab")
		)
		(fp_line
			(start 0.120396 0.2794)
			(end -0.12065 0.2794)
			(stroke
				(width 0.1)
				(type default)
			)
			(layer "F.Fab")
		)
		(fp_line
			(start 0.120396 0.3048)
			(end 0.120396 0.2794)
			(stroke
				(width 0.1)
				(type default)
			)
			(layer "F.Fab")
		)
		(fp_line
			(start 0.12065 -0.3048)
			(end 0.67945 -0.3048)
			(stroke
				(width 0.1)
				(type default)
			)
			(layer "F.Fab")
		)
		(fp_line
			(start 0.12065 -0.2794)
			(end 0.12065 -0.3048)
			(stroke
				(width 0.1)
				(type default)
			)
			(layer "F.Fab")
		)
		(fp_line
			(start 0.67945 -0.3048)
			(end 0.67945 0.3048)
			(stroke
				(width 0.1)
				(type default)
			)
			(layer "F.Fab")
		)
		(fp_line
			(start 0.67945 0.3048)
			(end 0.120396 0.3048)
			(stroke
				(width 0.1)
				(type default)
			)
			(layer "F.Fab")
		)
		(pad "1" smd circle
			(at -0.40005 0)
			(size 0 0)
			(layers "F.Cu" "F.Mask" "F.Paste")
			(net "P3V3_AUX")
		)
		(pad "2" smd circle
			(at 0.40005 0)
			(size 0 0)
			(layers "F.Cu" "F.Mask" "F.Paste")
			(net "SMB_BIC_I2C9_MUX1_SSD8_R_SCL")
		)
	)
	(footprint ""
		(layer "F.Cu")
		(at 127.658114 -254.194564)
		(property "Reference" "C199"
			(at 0 0 0)
			(layer "F.SilkS")
			(hide yes)
			(effects
				(font
					(size 1.27 1.27)
				)
			)
		)
		(property "Value" ""
			(at 0 0 0)
			(layer "F.Fab")
			(effects
				(font
					(size 1.27 1.27)
				)
			)
		)
		(duplicate_pad_numbers_are_jumpers no)
		(fp_line
			(start -0.7874 -0.4064)
			(end 0.7874 -0.4064)
			(stroke
				(width 0.1524)
				(type default)
			)
			(layer "F.SilkS")
		)
		(fp_line
			(start -0.7874 0.4064)
			(end -0.7874 -0.4064)
			(stroke
				(width 0.1524)
				(type default)
			)
			(layer "F.SilkS")
		)
		(fp_line
			(start 0.7874 -0.4064)
			(end 0.7874 0.4064)
			(stroke
				(width 0.1524)
				(type default)
			)
			(layer "F.SilkS")
		)
		(fp_line
			(start 0.7874 0.4064)
			(end -0.7874 0.4064)
			(stroke
				(width 0.1524)
				(type default)
			)
			(layer "F.SilkS")
		)
		(fp_line
			(start -0.67945 -0.305054)
			(end -0.12065 -0.305054)
			(stroke
				(width 0.1)
				(type default)
			)
			(layer "F.Fab")
		)
		(fp_line
			(start -0.67945 0.3048)
			(end -0.67945 -0.305054)
			(stroke
				(width 0.1)
				(type default)
			)
			(layer "F.Fab")
		)
		(fp_line
			(start -0.12065 -0.305054)
			(end -0.12065 -0.2794)
			(stroke
				(width 0.1)
				(type default)
			)
			(layer "F.Fab")
		)
		(fp_line
			(start -0.12065 -0.2794)
			(end 0.12065 -0.2794)
			(stroke
				(width 0.1)
				(type default)
			)
			(layer "F.Fab")
		)
		(fp_line
			(start -0.12065 0.2794)
			(end -0.12065 0.3048)
			(stroke
				(width 0.1)
				(type default)
			)
			(layer "F.Fab")
		)
		(fp_line
			(start -0.12065 0.3048)
			(end -0.67945 0.3048)
			(stroke
				(width 0.1)
				(type default)
			)
			(layer "F.Fab")
		)
		(fp_line
			(start 0.120396 0.2794)
			(end -0.12065 0.2794)
			(stroke
				(width 0.1)
				(type default)
			)
			(layer "F.Fab")
		)
		(fp_line
			(start 0.120396 0.3048)
			(end 0.120396 0.2794)
			(stroke
				(width 0.1)
				(type default)
			)
			(layer "F.Fab")
		)
		(fp_line
			(start 0.12065 -0.3048)
			(end 0.67945 -0.3048)
			(stroke
				(width 0.1)
				(type default)
			)
			(layer "F.Fab")
		)
		(fp_line
			(start 0.12065 -0.2794)
			(end 0.12065 -0.3048)
			(stroke
				(width 0.1)
				(type default)
			)
			(layer "F.Fab")
		)
		(fp_line
			(start 0.67945 -0.3048)
			(end 0.67945 0.3048)
			(stroke
				(width 0.1)
				(type default)
			)
			(layer "F.Fab")
		)
		(fp_line
			(start 0.67945 0.3048)
			(end 0.120396 0.3048)
			(stroke
				(width 0.1)
				(type default)
			)
			(layer "F.Fab")
		)
		(pad "1" smd circle
			(at -0.40005 0)
			(size 0 0)
			(layers "F.Cu" "F.Mask" "F.Paste")
			(net "P0V8_PEX0_AVRRDY")
		)
		(pad "2" smd circle
			(at 0.40005 0)
			(size 0 0)
			(layers "F.Cu" "F.Mask" "F.Paste")
			(net "GND")
		)
	)
	(footprint ""
		(layer "F.Cu")
		(at 395.247368 -21.37156)
		(property "Reference" "C3965"
			(at 0 0 0)
			(layer "F.SilkS")
			(hide yes)
			(effects
				(font
					(size 1.27 1.27)
				)
			)
		)
		(property "Value" ""
			(at 0 0 0)
			(layer "F.Fab")
			(effects
				(font
					(size 1.27 1.27)
				)
			)
		)
		(duplicate_pad_numbers_are_jumpers no)
		(fp_line
			(start -0.7874 -0.4064)
			(end 0.7874 -0.4064)
			(stroke
				(width 0.1524)
				(type default)
			)
			(layer "F.SilkS")
		)
		(fp_line
			(start -0.7874 0.4064)
			(end -0.7874 -0.4064)
			(stroke
				(width 0.1524)
				(type default)
			)
			(layer "F.SilkS")
		)
		(fp_line
			(start 0.7874 -0.4064)
			(end 0.7874 0.4064)
			(stroke
				(width 0.1524)
				(type default)
			)
			(layer "F.SilkS")
		)
		(fp_line
			(start 0.7874 0.4064)
			(end -0.7874 0.4064)
			(stroke
				(width 0.1524)
				(type default)
			)
			(layer "F.SilkS")
		)
		(fp_line
			(start -0.67945 -0.305054)
			(end -0.12065 -0.305054)
			(stroke
				(width 0.1)
				(type default)
			)
			(layer "F.Fab")
		)
		(fp_line
			(start -0.67945 0.3048)
			(end -0.67945 -0.305054)
			(stroke
				(width 0.1)
				(type default)
			)
			(layer "F.Fab")
		)
		(fp_line
			(start -0.12065 -0.305054)
			(end -0.12065 -0.2794)
			(stroke
				(width 0.1)
				(type default)
			)
			(layer "F.Fab")
		)
		(fp_line
			(start -0.12065 -0.2794)
			(end 0.12065 -0.2794)
			(stroke
				(width 0.1)
				(type default)
			)
			(layer "F.Fab")
		)
		(fp_line
			(start -0.12065 0.2794)
			(end -0.12065 0.3048)
			(stroke
				(width 0.1)
				(type default)
			)
			(layer "F.Fab")
		)
		(fp_line
			(start -0.12065 0.3048)
			(end -0.67945 0.3048)
			(stroke
				(width 0.1)
				(type default)
			)
			(layer "F.Fab")
		)
		(fp_line
			(start 0.120396 0.2794)
			(end -0.12065 0.2794)
			(stroke
				(width 0.1)
				(type default)
			)
			(layer "F.Fab")
		)
		(fp_line
			(start 0.120396 0.3048)
			(end 0.120396 0.2794)
			(stroke
				(width 0.1)
				(type default)
			)
			(layer "F.Fab")
		)
		(fp_line
			(start 0.12065 -0.3048)
			(end 0.67945 -0.3048)
			(stroke
				(width 0.1)
				(type default)
			)
			(layer "F.Fab")
		)
		(fp_line
			(start 0.12065 -0.2794)
			(end 0.12065 -0.3048)
			(stroke
				(width 0.1)
				(type default)
			)
			(layer "F.Fab")
		)
		(fp_line
			(start 0.67945 -0.3048)
			(end 0.67945 0.3048)
			(stroke
				(width 0.1)
				(type default)
			)
			(layer "F.Fab")
		)
		(fp_line
			(start 0.67945 0.3048)
			(end 0.120396 0.3048)
			(stroke
				(width 0.1)
				(type default)
			)
			(layer "F.Fab")
		)
		(pad "1" smd circle
			(at -0.40005 0)
			(size 0 0)
			(layers "F.Cu" "F.Mask" "F.Paste")
			(net "P12V_SSD13")
		)
		(pad "2" smd circle
			(at 0.40005 0)
			(size 0 0)
			(layers "F.Cu" "F.Mask" "F.Paste")
			(net "GND")
		)
	)
	(footprint ""
		(layer "F.Cu")
		(at 74.697082 -356.244906 90)
		(property "Reference" "C142"
			(at 0 0 90)
			(layer "F.SilkS")
			(hide yes)
			(effects
				(font
					(size 1.27 1.27)
				)
			)
		)
		(property "Value" ""
			(at 0 0 90)
			(layer "F.Fab")
			(effects
				(font
					(size 1.27 1.27)
				)
			)
		)
		(duplicate_pad_numbers_are_jumpers no)
		(fp_line
			(start 0.299974 -0.150114)
			(end 0.299974 0.150114)
			(stroke
				(width 0.1)
				(type default)
			)
			(layer "F.Fab")
		)
		(fp_line
			(start -0.299974 -0.150114)
			(end 0.299974 -0.150114)
			(stroke
				(width 0.1)
				(type default)
			)
			(layer "F.Fab")
		)
		(fp_line
			(start 0.299974 0.150114)
			(end -0.299974 0.150114)
			(stroke
				(width 0.1)
				(type default)
			)
			(layer "F.Fab")
		)
		(fp_line
			(start -0.299974 0.150114)
			(end -0.299974 -0.150114)
			(stroke
				(width 0.1)
				(type default)
			)
			(layer "F.Fab")
		)
		(pad "1" smd rect
			(at -0.2667 0 90)
			(size 0.3048 0.381)
			(layers "F.Cu" "F.Mask" "F.Paste")
			(net "P5E_PEX0_STN6_TX_DN<105>")
		)
		(pad "2" smd rect
			(at 0.2667 0 90)
			(size 0.3048 0.381)
			(layers "F.Cu" "F.Mask" "F.Paste")
			(net "P5E_PEX0_STN6_TX_C_DN<105>")
		)
	)
	(footprint ""
		(layer "F.Cu")
		(at 420.474902 -48.753014 180)
		(property "Reference" "C336"
			(at 0 0 180)
			(layer "F.SilkS")
			(hide yes)
			(effects
				(font
					(size 1.27 1.27)
				)
			)
		)
		(property "Value" ""
			(at 0 0 180)
			(layer "F.Fab")
			(effects
				(font
					(size 1.27 1.27)
				)
			)
		)
		(duplicate_pad_numbers_are_jumpers no)
		(fp_line
			(start 0.7874 0.4064)
			(end -0.7874 0.4064)
			(stroke
				(width 0.1524)
				(type default)
			)
			(layer "F.SilkS")
		)
		(fp_line
			(start 0.7874 -0.4064)
			(end 0.7874 0.4064)
			(stroke
				(width 0.1524)
				(type default)
			)
			(layer "F.SilkS")
		)
		(fp_line
			(start -0.7874 0.4064)
			(end -0.7874 -0.4064)
			(stroke
				(width 0.1524)
				(type default)
			)
			(layer "F.SilkS")
		)
		(fp_line
			(start -0.7874 -0.4064)
			(end 0.7874 -0.4064)
			(stroke
				(width 0.1524)
				(type default)
			)
			(layer "F.SilkS")
		)
		(fp_line
			(start 0.67945 0.3048)
			(end 0.120396 0.3048)
			(stroke
				(width 0.1)
				(type default)
			)
			(layer "F.Fab")
		)
		(fp_line
			(start 0.67945 -0.3048)
			(end 0.67945 0.3048)
			(stroke
				(width 0.1)
				(type default)
			)
			(layer "F.Fab")
		)
		(fp_line
			(start 0.12065 -0.2794)
			(end 0.12065 -0.3048)
			(stroke
				(width 0.1)
				(type default)
			)
			(layer "F.Fab")
		)
		(fp_line
			(start 0.12065 -0.3048)
			(end 0.67945 -0.3048)
			(stroke
				(width 0.1)
				(type default)
			)
			(layer "F.Fab")
		)
		(fp_line
			(start 0.120396 0.3048)
			(end 0.120396 0.2794)
			(stroke
				(width 0.1)
				(type default)
			)
			(layer "F.Fab")
		)
		(fp_line
			(start 0.120396 0.2794)
			(end -0.12065 0.2794)
			(stroke
				(width 0.1)
				(type default)
			)
			(layer "F.Fab")
		)
		(fp_line
			(start -0.12065 0.3048)
			(end -0.67945 0.3048)
			(stroke
				(width 0.1)
				(type default)
			)
			(layer "F.Fab")
		)
		(fp_line
			(start -0.12065 0.2794)
			(end -0.12065 0.3048)
			(stroke
				(width 0.1)
				(type default)
			)
			(layer "F.Fab")
		)
		(fp_line
			(start -0.12065 -0.2794)
			(end 0.12065 -0.2794)
			(stroke
				(width 0.1)
				(type default)
			)
			(layer "F.Fab")
		)
		(fp_line
			(start -0.12065 -0.305054)
			(end -0.12065 -0.2794)
			(stroke
				(width 0.1)
				(type default)
			)
			(layer "F.Fab")
		)
		(fp_line
			(start -0.67945 0.3048)
			(end -0.67945 -0.305054)
			(stroke
				(width 0.1)
				(type default)
			)
			(layer "F.Fab")
		)
		(fp_line
			(start -0.67945 -0.305054)
			(end -0.12065 -0.305054)
			(stroke
				(width 0.1)
				(type default)
			)
			(layer "F.Fab")
		)
		(pad "1" smd circle
			(at -0.40005 0 180)
			(size 0 0)
			(layers "F.Cu" "F.Mask" "F.Paste")
			(net "P3V3_AUX")
		)
		(pad "2" smd circle
			(at 0.40005 0 180)
			(size 0 0)
			(layers "F.Cu" "F.Mask" "F.Paste")
			(net "GND")
		)
	)
	(footprint ""
		(layer "F.Cu")
		(at 290.264342 -141.6558 180)
		(property "Reference" "R239"
			(at 0 0 180)
			(layer "F.SilkS")
			(hide yes)
			(effects
				(font
					(size 1.27 1.27)
				)
			)
		)
		(property "Value" ""
			(at 0 0 180)
			(layer "F.Fab")
			(effects
				(font
					(size 1.27 1.27)
				)
			)
		)
		(duplicate_pad_numbers_are_jumpers no)
		(fp_line
			(start 0.7874 0.4064)
			(end -0.7874 0.4064)
			(stroke
				(width 0.1524)
				(type default)
			)
			(layer "F.SilkS")
		)
		(fp_line
			(start 0.7874 -0.4064)
			(end 0.7874 0.4064)
			(stroke
				(width 0.1524)
				(type default)
			)
			(layer "F.SilkS")
		)
		(fp_line
			(start -0.7874 0.4064)
			(end -0.7874 -0.4064)
			(stroke
				(width 0.1524)
				(type default)
			)
			(layer "F.SilkS")
		)
		(fp_line
			(start -0.7874 -0.4064)
			(end 0.7874 -0.4064)
			(stroke
				(width 0.1524)
				(type default)
			)
			(layer "F.SilkS")
		)
		(fp_line
			(start 0.67945 0.3048)
			(end 0.120396 0.3048)
			(stroke
				(width 0.1)
				(type default)
			)
			(layer "F.Fab")
		)
		(fp_line
			(start 0.67945 -0.3048)
			(end 0.67945 0.3048)
			(stroke
				(width 0.1)
				(type default)
			)
			(layer "F.Fab")
		)
		(fp_line
			(start 0.12065 -0.2794)
			(end 0.12065 -0.3048)
			(stroke
				(width 0.1)
				(type default)
			)
			(layer "F.Fab")
		)
		(fp_line
			(start 0.12065 -0.3048)
			(end 0.67945 -0.3048)
			(stroke
				(width 0.1)
				(type default)
			)
			(layer "F.Fab")
		)
		(fp_line
			(start 0.120396 0.3048)
			(end 0.120396 0.2794)
			(stroke
				(width 0.1)
				(type default)
			)
			(layer "F.Fab")
		)
		(fp_line
			(start 0.120396 0.2794)
			(end -0.12065 0.2794)
			(stroke
				(width 0.1)
				(type default)
			)
			(layer "F.Fab")
		)
		(fp_line
			(start -0.12065 0.3048)
			(end -0.67945 0.3048)
			(stroke
				(width 0.1)
				(type default)
			)
			(layer "F.Fab")
		)
		(fp_line
			(start -0.12065 0.2794)
			(end -0.12065 0.3048)
			(stroke
				(width 0.1)
				(type default)
			)
			(layer "F.Fab")
		)
		(fp_line
			(start -0.12065 -0.2794)
			(end 0.12065 -0.2794)
			(stroke
				(width 0.1)
				(type default)
			)
			(layer "F.Fab")
		)
		(fp_line
			(start -0.12065 -0.305054)
			(end -0.12065 -0.2794)
			(stroke
				(width 0.1)
				(type default)
			)
			(layer "F.Fab")
		)
		(fp_line
			(start -0.67945 0.3048)
			(end -0.67945 -0.305054)
			(stroke
				(width 0.1)
				(type default)
			)
			(layer "F.Fab")
		)
		(fp_line
			(start -0.67945 -0.305054)
			(end -0.12065 -0.305054)
			(stroke
				(width 0.1)
				(type default)
			)
			(layer "F.Fab")
		)
		(pad "1" smd circle
			(at -0.40005 0 180)
			(size 0 0)
			(layers "F.Cu" "F.Mask" "F.Paste")
			(net "RST_SMB_NIC4_MUX_ISO_N")
		)
		(pad "2" smd circle
			(at 0.40005 0 180)
			(size 0 0)
			(layers "F.Cu" "F.Mask" "F.Paste")
			(net "P3V3_NIC4")
		)
	)
)
